(kicad_pcb
	(version 20260206)
	(generator "pcbnew")
	(generator_version "10.0")
	(general
		(thickness 1.6)
		(legacy_teardrops no)
	)
	(paper "A4")
	(title_block
		(title "03242023_DA0F0TMBIJ0_F0T_Motherboard_J_brd_V01_OCP.brd")
		(comment 1 "Grand Teton / footprints 449-455 of 6105")
	)
	(layers
		(0 "F.Cu" signal "TOP")
		(4 "In1.Cu" signal "GND")
		(6 "In2.Cu" signal "IN1")
		(8 "In3.Cu" signal "GND1")
		(10 "In4.Cu" signal "IN2")
		(12 "In5.Cu" signal "GND2")
		(14 "In6.Cu" signal "IN3")
		(16 "In7.Cu" signal "GND3")
		(18 "In8.Cu" signal "VCC")
		(20 "In9.Cu" signal "VCC1")
		(22 "In10.Cu" signal "GND4")
		(24 "In11.Cu" signal "IN4")
		(26 "In12.Cu" signal "GND5")
		(28 "In13.Cu" signal "IN5")
		(30 "In14.Cu" signal "GND6")
		(32 "In15.Cu" signal "IN6")
		(34 "In16.Cu" signal "GND7")
		(2 "B.Cu" signal "BOTTOM")
		(9 "F.Adhes" user "F.Adhesive")
		(11 "B.Adhes" user "B.Adhesive")
		(13 "F.Paste" user "Package Geometry/Pastemask Top")
		(15 "B.Paste" user "Package Geometry/Pastemask Bottom")
		(5 "F.SilkS" user "Ref Des/Silkscreen Top")
		(7 "B.SilkS" user "Ref Des/Silkscreen Bottom")
		(1 "F.Mask" user "Board Geometry/Soldermask Top")
		(3 "B.Mask" user "Board Geometry/Soldermask Bottom")
		(17 "Dwgs.User" user "User.Drawings")
		(19 "Cmts.User" user "User.Comments")
		(21 "Eco1.User" user "User.Eco1")
		(23 "Eco2.User" user "User.Eco2")
		(25 "Edge.Cuts" user "Board Geometry/Outline")
		(27 "Margin" user)
		(31 "F.CrtYd" user "Package Geometry/Place Bound Top")
		(29 "B.CrtYd" user "Package Geometry/Place Bound Bottom")
		(35 "F.Fab" user "Ref Des/Assembly Top")
		(33 "B.Fab" user "Ref Des/Assembly Bottom")
	)
	(footprint ""
		(layer "F.Cu")
		(at 382.165352 -345.393264 90)
		(property "Reference" "PC226"
			(at 0 0 90)
			(layer "F.SilkS")
			(hide yes)
			(effects
				(font
					(size 1.27 1.27)
				)
			)
		)
		(property "Value" ""
			(at 0 0 90)
			(layer "F.Fab")
			(effects
				(font
					(size 1.27 1.27)
				)
			)
		)
		(duplicate_pad_numbers_are_jumpers no)
		(fp_line
			(start 0.7874 -0.4064)
			(end 0.7874 0.4064)
			(stroke
				(width 0.1524)
				(type default)
			)
			(layer "F.SilkS")
		)
		(fp_line
			(start -0.7874 -0.4064)
			(end 0.7874 -0.4064)
			(stroke
				(width 0.1524)
				(type default)
			)
			(layer "F.SilkS")
		)
		(fp_line
			(start 0.7874 0.4064)
			(end -0.7874 0.4064)
			(stroke
				(width 0.1524)
				(type default)
			)
			(layer "F.SilkS")
		)
		(fp_line
			(start -0.7874 0.4064)
			(end -0.7874 -0.4064)
			(stroke
				(width 0.1524)
				(type default)
			)
			(layer "F.SilkS")
		)
		(fp_line
			(start -0.12065 -0.305054)
			(end -0.12065 -0.2794)
			(stroke
				(width 0.1)
				(type default)
			)
			(layer "F.Fab")
		)
		(fp_line
			(start -0.67945 -0.305054)
			(end -0.12065 -0.305054)
			(stroke
				(width 0.1)
				(type default)
			)
			(layer "F.Fab")
		)
		(fp_line
			(start 0.67945 -0.3048)
			(end 0.67945 0.3048)
			(stroke
				(width 0.1)
				(type default)
			)
			(layer "F.Fab")
		)
		(fp_line
			(start 0.12065 -0.3048)
			(end 0.67945 -0.3048)
			(stroke
				(width 0.1)
				(type default)
			)
			(layer "F.Fab")
		)
		(fp_line
			(start 0.12065 -0.2794)
			(end 0.12065 -0.3048)
			(stroke
				(width 0.1)
				(type default)
			)
			(layer "F.Fab")
		)
		(fp_line
			(start -0.12065 -0.2794)
			(end 0.12065 -0.2794)
			(stroke
				(width 0.1)
				(type default)
			)
			(layer "F.Fab")
		)
		(fp_line
			(start 0.120396 0.2794)
			(end -0.12065 0.2794)
			(stroke
				(width 0.1)
				(type default)
			)
			(layer "F.Fab")
		)
		(fp_line
			(start -0.12065 0.2794)
			(end -0.12065 0.3048)
			(stroke
				(width 0.1)
				(type default)
			)
			(layer "F.Fab")
		)
		(fp_line
			(start 0.67945 0.3048)
			(end 0.120396 0.3048)
			(stroke
				(width 0.1)
				(type default)
			)
			(layer "F.Fab")
		)
		(fp_line
			(start 0.120396 0.3048)
			(end 0.120396 0.2794)
			(stroke
				(width 0.1)
				(type default)
			)
			(layer "F.Fab")
		)
		(fp_line
			(start -0.12065 0.3048)
			(end -0.67945 0.3048)
			(stroke
				(width 0.1)
				(type default)
			)
			(layer "F.Fab")
		)
		(fp_line
			(start -0.67945 0.3048)
			(end -0.67945 -0.305054)
			(stroke
				(width 0.1)
				(type default)
			)
			(layer "F.Fab")
		)
		(pad "1" smd circle
			(at -0.40005 0 90)
			(size 0 0)
			(layers "F.Cu" "F.Mask" "F.Paste")
			(net "PVCCIN_CPU0_VDD8")
		)
		(pad "2" smd circle
			(at 0.40005 0 90)
			(size 0 0)
			(layers "F.Cu" "F.Mask" "F.Paste")
			(net "GND")
		)
	)
	(footprint ""
		(layer "F.Cu")
		(at 367.44783 -245.634002 -90)
		(property "Reference" "C403"
			(at 0 0 270)
			(layer "F.SilkS")
			(hide yes)
			(effects
				(font
					(size 1.27 1.27)
				)
			)
		)
		(property "Value" ""
			(at 0 0 270)
			(layer "F.Fab")
			(effects
				(font
					(size 1.27 1.27)
				)
			)
		)
		(duplicate_pad_numbers_are_jumpers no)
		(fp_line
			(start -0.7874 0.4064)
			(end -0.7874 -0.4064)
			(stroke
				(width 0.1524)
				(type default)
			)
			(layer "F.SilkS")
		)
		(fp_line
			(start 0.7874 0.4064)
			(end -0.7874 0.4064)
			(stroke
				(width 0.1524)
				(type default)
			)
			(layer "F.SilkS")
		)
		(fp_line
			(start -0.7874 -0.4064)
			(end 0.7874 -0.4064)
			(stroke
				(width 0.1524)
				(type default)
			)
			(layer "F.SilkS")
		)
		(fp_line
			(start 0.7874 -0.4064)
			(end 0.7874 0.4064)
			(stroke
				(width 0.1524)
				(type default)
			)
			(layer "F.SilkS")
		)
		(fp_line
			(start -0.67945 0.3048)
			(end -0.67945 -0.305054)
			(stroke
				(width 0.1)
				(type default)
			)
			(layer "F.Fab")
		)
		(fp_line
			(start -0.12065 0.3048)
			(end -0.67945 0.3048)
			(stroke
				(width 0.1)
				(type default)
			)
			(layer "F.Fab")
		)
		(fp_line
			(start 0.120396 0.3048)
			(end 0.120396 0.2794)
			(stroke
				(width 0.1)
				(type default)
			)
			(layer "F.Fab")
		)
		(fp_line
			(start 0.67945 0.3048)
			(end 0.120396 0.3048)
			(stroke
				(width 0.1)
				(type default)
			)
			(layer "F.Fab")
		)
		(fp_line
			(start -0.12065 0.2794)
			(end -0.12065 0.3048)
			(stroke
				(width 0.1)
				(type default)
			)
			(layer "F.Fab")
		)
		(fp_line
			(start 0.120396 0.2794)
			(end -0.12065 0.2794)
			(stroke
				(width 0.1)
				(type default)
			)
			(layer "F.Fab")
		)
		(fp_line
			(start -0.12065 -0.2794)
			(end 0.12065 -0.2794)
			(stroke
				(width 0.1)
				(type default)
			)
			(layer "F.Fab")
		)
		(fp_line
			(start 0.12065 -0.2794)
			(end 0.12065 -0.3048)
			(stroke
				(width 0.1)
				(type default)
			)
			(layer "F.Fab")
		)
		(fp_line
			(start 0.12065 -0.3048)
			(end 0.67945 -0.3048)
			(stroke
				(width 0.1)
				(type default)
			)
			(layer "F.Fab")
		)
		(fp_line
			(start 0.67945 -0.3048)
			(end 0.67945 0.3048)
			(stroke
				(width 0.1)
				(type default)
			)
			(layer "F.Fab")
		)
		(fp_line
			(start -0.67945 -0.305054)
			(end -0.12065 -0.305054)
			(stroke
				(width 0.1)
				(type default)
			)
			(layer "F.Fab")
		)
		(fp_line
			(start -0.12065 -0.305054)
			(end -0.12065 -0.2794)
			(stroke
				(width 0.1)
				(type default)
			)
			(layer "F.Fab")
		)
		(pad "1" smd circle
			(at -0.40005 0 270)
			(size 0 0)
			(layers "F.Cu" "F.Mask" "F.Paste")
			(net "PVCCD_HV_CPU0")
		)
		(pad "2" smd circle
			(at 0.40005 0 270)
			(size 0 0)
			(layers "F.Cu" "F.Mask" "F.Paste")
			(net "GND")
		)
	)
	(footprint ""
		(layer "F.Cu")
		(at 388.014972 -76.171044 90)
		(property "Reference" "PC1233"
			(at 0 0 90)
			(layer "F.SilkS")
			(hide yes)
			(effects
				(font
					(size 1.27 1.27)
				)
			)
		)
		(property "Value" ""
			(at 0 0 90)
			(layer "F.Fab")
			(effects
				(font
					(size 1.27 1.27)
				)
			)
		)
		(duplicate_pad_numbers_are_jumpers no)
		(fp_line
			(start 1.524 -0.762)
			(end 1.524 0.762)
			(stroke
				(width 0.1524)
				(type default)
			)
			(layer "F.SilkS")
		)
		(fp_line
			(start -1.524 -0.762)
			(end 1.524 -0.762)
			(stroke
				(width 0.1524)
				(type default)
			)
			(layer "F.SilkS")
		)
		(fp_line
			(start 1.524 0.762)
			(end -1.524 0.762)
			(stroke
				(width 0.1524)
				(type default)
			)
			(layer "F.SilkS")
		)
		(fp_line
			(start -1.524 0.762)
			(end -1.524 -0.762)
			(stroke
				(width 0.1524)
				(type default)
			)
			(layer "F.SilkS")
		)
		(fp_line
			(start 1.1049 -0.724916)
			(end -1.1049 -0.724916)
			(stroke
				(width 0.1)
				(type default)
			)
			(layer "F.Fab")
		)
		(fp_line
			(start -1.1049 -0.724916)
			(end -1.1049 0.724916)
			(stroke
				(width 0.1)
				(type default)
			)
			(layer "F.Fab")
		)
		(fp_line
			(start 1.1049 0.724916)
			(end 1.1049 -0.724916)
			(stroke
				(width 0.1)
				(type default)
			)
			(layer "F.Fab")
		)
		(fp_line
			(start -1.1049 0.724916)
			(end 1.1049 0.724916)
			(stroke
				(width 0.1)
				(type default)
			)
			(layer "F.Fab")
		)
		(pad "1" smd rect
			(at -0.889 0 270)
			(size 1.016 1.27)
			(layers "F.Cu" "F.Mask" "F.Paste")
			(net "SW_P1V8_PCH_AUX_FLT")
		)
		(pad "2" smd rect
			(at 0.889 0 270)
			(size 1.016 1.27)
			(layers "F.Cu" "F.Mask" "F.Paste")
			(net "GND")
		)
	)
	(footprint ""
		(layer "F.Cu")
		(at 119.508016 -251.375672 90)
		(property "Reference" "C258"
			(at 0 0 90)
			(layer "F.SilkS")
			(hide yes)
			(effects
				(font
					(size 1.27 1.27)
				)
			)
		)
		(property "Value" ""
			(at 0 0 90)
			(layer "F.Fab")
			(effects
				(font
					(size 1.27 1.27)
				)
			)
		)
		(duplicate_pad_numbers_are_jumpers no)
		(fp_line
			(start 0.7874 -0.4064)
			(end 0.7874 0.4064)
			(stroke
				(width 0.1524)
				(type default)
			)
			(layer "F.SilkS")
		)
		(fp_line
			(start -0.7874 -0.4064)
			(end 0.7874 -0.4064)
			(stroke
				(width 0.1524)
				(type default)
			)
			(layer "F.SilkS")
		)
		(fp_line
			(start 0.7874 0.4064)
			(end -0.7874 0.4064)
			(stroke
				(width 0.1524)
				(type default)
			)
			(layer "F.SilkS")
		)
		(fp_line
			(start -0.7874 0.4064)
			(end -0.7874 -0.4064)
			(stroke
				(width 0.1524)
				(type default)
			)
			(layer "F.SilkS")
		)
		(fp_line
			(start -0.12065 -0.305054)
			(end -0.12065 -0.2794)
			(stroke
				(width 0.1)
				(type default)
			)
			(layer "F.Fab")
		)
		(fp_line
			(start -0.67945 -0.305054)
			(end -0.12065 -0.305054)
			(stroke
				(width 0.1)
				(type default)
			)
			(layer "F.Fab")
		)
		(fp_line
			(start 0.67945 -0.3048)
			(end 0.67945 0.3048)
			(stroke
				(width 0.1)
				(type default)
			)
			(layer "F.Fab")
		)
		(fp_line
			(start 0.12065 -0.3048)
			(end 0.67945 -0.3048)
			(stroke
				(width 0.1)
				(type default)
			)
			(layer "F.Fab")
		)
		(fp_line
			(start 0.12065 -0.2794)
			(end 0.12065 -0.3048)
			(stroke
				(width 0.1)
				(type default)
			)
			(layer "F.Fab")
		)
		(fp_line
			(start -0.12065 -0.2794)
			(end 0.12065 -0.2794)
			(stroke
				(width 0.1)
				(type default)
			)
			(layer "F.Fab")
		)
		(fp_line
			(start 0.120396 0.2794)
			(end -0.12065 0.2794)
			(stroke
				(width 0.1)
				(type default)
			)
			(layer "F.Fab")
		)
		(fp_line
			(start -0.12065 0.2794)
			(end -0.12065 0.3048)
			(stroke
				(width 0.1)
				(type default)
			)
			(layer "F.Fab")
		)
		(fp_line
			(start 0.67945 0.3048)
			(end 0.120396 0.3048)
			(stroke
				(width 0.1)
				(type default)
			)
			(layer "F.Fab")
		)
		(fp_line
			(start 0.120396 0.3048)
			(end 0.120396 0.2794)
			(stroke
				(width 0.1)
				(type default)
			)
			(layer "F.Fab")
		)
		(fp_line
			(start -0.12065 0.3048)
			(end -0.67945 0.3048)
			(stroke
				(width 0.1)
				(type default)
			)
			(layer "F.Fab")
		)
		(fp_line
			(start -0.67945 0.3048)
			(end -0.67945 -0.305054)
			(stroke
				(width 0.1)
				(type default)
			)
			(layer "F.Fab")
		)
		(pad "1" smd circle
			(at -0.40005 0 90)
			(size 0 0)
			(layers "F.Cu" "F.Mask" "F.Paste")
			(net "PVCCIN_CPU1")
		)
		(pad "2" smd circle
			(at 0.40005 0 90)
			(size 0 0)
			(layers "F.Cu" "F.Mask" "F.Paste")
			(net "GND")
		)
	)
	(footprint ""
		(layer "F.Cu")
		(at 317.396622 -54.803548)
		(property "Reference" "R623"
			(at 0 0 0)
			(layer "F.SilkS")
			(hide yes)
			(effects
				(font
					(size 1.27 1.27)
				)
			)
		)
		(property "Value" ""
			(at 0 0 0)
			(layer "F.Fab")
			(effects
				(font
					(size 1.27 1.27)
				)
			)
		)
		(duplicate_pad_numbers_are_jumpers no)
		(fp_line
			(start -0.7874 -0.4064)
			(end 0.7874 -0.4064)
			(stroke
				(width 0.1524)
				(type default)
			)
			(layer "F.SilkS")
		)
		(fp_line
			(start -0.7874 0.4064)
			(end -0.7874 -0.4064)
			(stroke
				(width 0.1524)
				(type default)
			)
			(layer "F.SilkS")
		)
		(fp_line
			(start 0.7874 -0.4064)
			(end 0.7874 0.4064)
			(stroke
				(width 0.1524)
				(type default)
			)
			(layer "F.SilkS")
		)
		(fp_line
			(start 0.7874 0.4064)
			(end -0.7874 0.4064)
			(stroke
				(width 0.1524)
				(type default)
			)
			(layer "F.SilkS")
		)
		(fp_line
			(start -0.67945 -0.305054)
			(end -0.12065 -0.305054)
			(stroke
				(width 0.1)
				(type default)
			)
			(layer "F.Fab")
		)
		(fp_line
			(start -0.67945 0.3048)
			(end -0.67945 -0.305054)
			(stroke
				(width 0.1)
				(type default)
			)
			(layer "F.Fab")
		)
		(fp_line
			(start -0.12065 -0.305054)
			(end -0.12065 -0.2794)
			(stroke
				(width 0.1)
				(type default)
			)
			(layer "F.Fab")
		)
		(fp_line
			(start -0.12065 -0.2794)
			(end 0.12065 -0.2794)
			(stroke
				(width 0.1)
				(type default)
			)
			(layer "F.Fab")
		)
		(fp_line
			(start -0.12065 0.2794)
			(end -0.12065 0.3048)
			(stroke
				(width 0.1)
				(type default)
			)
			(layer "F.Fab")
		)
		(fp_line
			(start -0.12065 0.3048)
			(end -0.67945 0.3048)
			(stroke
				(width 0.1)
				(type default)
			)
			(layer "F.Fab")
		)
		(fp_line
			(start 0.120396 0.2794)
			(end -0.12065 0.2794)
			(stroke
				(width 0.1)
				(type default)
			)
			(layer "F.Fab")
		)
		(fp_line
			(start 0.120396 0.3048)
			(end 0.120396 0.2794)
			(stroke
				(width 0.1)
				(type default)
			)
			(layer "F.Fab")
		)
		(fp_line
			(start 0.12065 -0.3048)
			(end 0.67945 -0.3048)
			(stroke
				(width 0.1)
				(type default)
			)
			(layer "F.Fab")
		)
		(fp_line
			(start 0.12065 -0.2794)
			(end 0.12065 -0.3048)
			(stroke
				(width 0.1)
				(type default)
			)
			(layer "F.Fab")
		)
		(fp_line
			(start 0.67945 -0.3048)
			(end 0.67945 0.3048)
			(stroke
				(width 0.1)
				(type default)
			)
			(layer "F.Fab")
		)
		(fp_line
			(start 0.67945 0.3048)
			(end 0.120396 0.3048)
			(stroke
				(width 0.1)
				(type default)
			)
			(layer "F.Fab")
		)
		(pad "1" smd circle
			(at -0.40005 0)
			(size 0 0)
			(layers "F.Cu" "F.Mask" "F.Paste")
			(net "P3V3_AUX")
		)
		(pad "2" smd circle
			(at 0.40005 0)
			(size 0 0)
			(layers "F.Cu" "F.Mask" "F.Paste")
			(net "FM_PCH_XTALSEL")
		)
	)
	(footprint ""
		(layer "F.Cu")
		(at 73.28408 -144.665192 180)
		(property "Reference" "PR566"
			(at 0 0 180)
			(layer "F.SilkS")
			(hide yes)
			(effects
				(font
					(size 1.27 1.27)
				)
			)
		)
		(property "Value" ""
			(at 0 0 180)
			(layer "F.Fab")
			(effects
				(font
					(size 1.27 1.27)
				)
			)
		)
		(duplicate_pad_numbers_are_jumpers no)
		(fp_line
			(start 0.7874 0.4064)
			(end -0.7874 0.4064)
			(stroke
				(width 0.1524)
				(type default)
			)
			(layer "F.SilkS")
		)
		(fp_line
			(start 0.7874 -0.4064)
			(end 0.7874 0.4064)
			(stroke
				(width 0.1524)
				(type default)
			)
			(layer "F.SilkS")
		)
		(fp_line
			(start -0.7874 0.4064)
			(end -0.7874 -0.4064)
			(stroke
				(width 0.1524)
				(type default)
			)
			(layer "F.SilkS")
		)
		(fp_line
			(start -0.7874 -0.4064)
			(end 0.7874 -0.4064)
			(stroke
				(width 0.1524)
				(type default)
			)
			(layer "F.SilkS")
		)
		(fp_line
			(start 0.67945 0.3048)
			(end 0.120396 0.3048)
			(stroke
				(width 0.1)
				(type default)
			)
			(layer "F.Fab")
		)
		(fp_line
			(start 0.67945 -0.3048)
			(end 0.67945 0.3048)
			(stroke
				(width 0.1)
				(type default)
			)
			(layer "F.Fab")
		)
		(fp_line
			(start 0.12065 -0.2794)
			(end 0.12065 -0.3048)
			(stroke
				(width 0.1)
				(type default)
			)
			(layer "F.Fab")
		)
		(fp_line
			(start 0.12065 -0.3048)
			(end 0.67945 -0.3048)
			(stroke
				(width 0.1)
				(type default)
			)
			(layer "F.Fab")
		)
		(fp_line
			(start 0.120396 0.3048)
			(end 0.120396 0.2794)
			(stroke
				(width 0.1)
				(type default)
			)
			(layer "F.Fab")
		)
		(fp_line
			(start 0.120396 0.2794)
			(end -0.12065 0.2794)
			(stroke
				(width 0.1)
				(type default)
			)
			(layer "F.Fab")
		)
		(fp_line
			(start -0.12065 0.3048)
			(end -0.67945 0.3048)
			(stroke
				(width 0.1)
				(type default)
			)
			(layer "F.Fab")
		)
		(fp_line
			(start -0.12065 0.2794)
			(end -0.12065 0.3048)
			(stroke
				(width 0.1)
				(type default)
			)
			(layer "F.Fab")
		)
		(fp_line
			(start -0.12065 -0.2794)
			(end 0.12065 -0.2794)
			(stroke
				(width 0.1)
				(type default)
			)
			(layer "F.Fab")
		)
		(fp_line
			(start -0.12065 -0.305054)
			(end -0.12065 -0.2794)
			(stroke
				(width 0.1)
				(type default)
			)
			(layer "F.Fab")
		)
		(fp_line
			(start -0.67945 0.3048)
			(end -0.67945 -0.305054)
			(stroke
				(width 0.1)
				(type default)
			)
			(layer "F.Fab")
		)
		(fp_line
			(start -0.67945 -0.305054)
			(end -0.12065 -0.305054)
			(stroke
				(width 0.1)
				(type default)
			)
			(layer "F.Fab")
		)
		(pad "1" smd circle
			(at -0.40005 0 180)
			(size 0 0)
			(layers "F.Cu" "F.Mask" "F.Paste")
			(net "VSENSE_PVCCINFAON_CPU1_DN")
		)
		(pad "2" smd circle
			(at 0.40005 0 180)
			(size 0 0)
			(layers "F.Cu" "F.Mask" "F.Paste")
			(net "GND")
		)
	)
	(footprint ""
		(layer "F.Cu")
		(at 322.90004 -160.50006)
		(property "Reference" "H88"
			(at -6.47192 -4.13131 0)
			(unlocked yes)
			(layer "F.SilkS")
			(effects
				(font
					(size 0.7874 0.5842)
					(thickness 0.1524)
				)
				(justify left)
			)
		)
		(property "Value" ""
			(at 0 0 0)
			(layer "F.Fab")
			(effects
				(font
					(size 1.27 1.27)
				)
			)
		)
		(duplicate_pad_numbers_are_jumpers no)
		(pad "1" thru_hole circle
			(at 0 0)
			(size 10.0076 10.0076)
			(drill 5.6134)
			(layers "*.Cu" "*.Mask")
			(remove_unused_layers no)
			(net "GND")
			(clearance -1.9431)
		)
	)
)
